# S9S_MB_2U (Grand Teton) — schematic netlist excerpt (pin names and nets, part order shuffled) for the footprints in the layout excerpt that follows; sources: Cadence DE-HDL packaged netlist, KiCad conversion of 03242023_DA0F0TMBIJ0_F0T_Motherboard_J_brd_V01_OCP.brd

C1006  Q_CAP  22UF 4V 20% X6S  pkg C0402  page 74 : A = PVCCIN_CPU0 ; B = GND
R4584  Q_RES  10K 1% EMPTY  pkg 0402LF  page 195 : A = P3V3_AUX ; B = FM_BOARD_BMC_SKU_ID0
C1249  Q_CAP  47UF 4V 20% X6S  pkg C0805  page 189 : A = P1V05_PCH_AUX ; B = GND

(kicad_pcb
	(version 20260206)
	(generator "pcbnew")
	(generator_version "10.0")
	(general
		(thickness 1.6)
		(legacy_teardrops no)
	)
	(paper "A4")
	(title_block
		(title "03242023_DA0F0TMBIJ0_F0T_Motherboard_J_brd_V01_OCP.brd")
		(comment 1 "Grand Teton / footprints 3936-3938 of 6105")
	)
	(layers
		(0 "F.Cu" signal "TOP")
		(4 "In1.Cu" signal "GND")
		(6 "In2.Cu" signal "IN1")
		(8 "In3.Cu" signal "GND1")
		(10 "In4.Cu" signal "IN2")
		(12 "In5.Cu" signal "GND2")
		(14 "In6.Cu" signal "IN3")
		(16 "In7.Cu" signal "GND3")
		(18 "In8.Cu" signal "VCC")
		(20 "In9.Cu" signal "VCC1")
		(22 "In10.Cu" signal "GND4")
		(24 "In11.Cu" signal "IN4")
		(26 "In12.Cu" signal "GND5")
		(28 "In13.Cu" signal "IN5")
		(30 "In14.Cu" signal "GND6")
		(32 "In15.Cu" signal "IN6")
		(34 "In16.Cu" signal "GND7")
		(2 "B.Cu" signal "BOTTOM")
		(9 "F.Adhes" user "F.Adhesive")
		(11 "B.Adhes" user "B.Adhesive")
		(13 "F.Paste" user "Package Geometry/Pastemask Top")
		(15 "B.Paste" user "Package Geometry/Pastemask Bottom")
		(5 "F.SilkS" user "Ref Des/Silkscreen Top")
		(7 "B.SilkS" user "Ref Des/Silkscreen Bottom")
		(1 "F.Mask" user "Board Geometry/Soldermask Top")
		(3 "B.Mask" user "Board Geometry/Soldermask Bottom")
		(17 "Dwgs.User" user "User.Drawings")
		(19 "Cmts.User" user "User.Comments")
		(21 "Eco1.User" user "User.Eco1")
		(23 "Eco2.User" user "User.Eco2")
		(25 "Edge.Cuts" user "Board Geometry/Outline")
		(27 "Margin" user)
		(31 "F.CrtYd" user "Package Geometry/Place Bound Top")
		(29 "B.CrtYd" user "Package Geometry/Place Bound Bottom")
		(35 "F.Fab" user "Ref Des/Assembly Top")
		(33 "B.Fab" user "Ref Des/Assembly Bottom")
	)
	(footprint ""
		(layer "F.Cu")
		(at 354.264214 -252.956314 -90)
		(property "Reference" "C1006"
			(at 0 0 270)
			(layer "F.SilkS")
			(hide yes)
			(effects
				(font
					(size 1.27 1.27)
				)
			)
		)
		(property "Value" ""
			(at 0 0 270)
			(layer "F.Fab")
			(effects
				(font
					(size 1.27 1.27)
				)
			)
		)
		(duplicate_pad_numbers_are_jumpers no)
		(fp_line
			(start -0.7874 0.4064)
			(end -0.7874 -0.4064)
			(stroke
				(width 0.1524)
				(type default)
			)
			(layer "F.SilkS")
		)
		(fp_line
			(start 0.7874 0.4064)
			(end -0.7874 0.4064)
			(stroke
				(width 0.1524)
				(type default)
			)
			(layer "F.SilkS")
		)
		(fp_line
			(start -0.7874 -0.4064)
			(end 0.7874 -0.4064)
			(stroke
				(width 0.1524)
				(type default)
			)
			(layer "F.SilkS")
		)
		(fp_line
			(start 0.7874 -0.4064)
			(end 0.7874 0.4064)
			(stroke
				(width 0.1524)
				(type default)
			)
			(layer "F.SilkS")
		)
		(fp_line
			(start -0.67945 0.3048)
			(end -0.67945 -0.305054)
			(stroke
				(width 0.1)
				(type default)
			)
			(layer "F.Fab")
		)
		(fp_line
			(start -0.12065 0.3048)
			(end -0.67945 0.3048)
			(stroke
				(width 0.1)
				(type default)
			)
			(layer "F.Fab")
		)
		(fp_line
			(start 0.120396 0.3048)
			(end 0.120396 0.2794)
			(stroke
				(width 0.1)
				(type default)
			)
			(layer "F.Fab")
		)
		(fp_line
			(start 0.67945 0.3048)
			(end 0.120396 0.3048)
			(stroke
				(width 0.1)
				(type default)
			)
			(layer "F.Fab")
		)
		(fp_line
			(start -0.12065 0.2794)
			(end -0.12065 0.3048)
			(stroke
				(width 0.1)
				(type default)
			)
			(layer "F.Fab")
		)
		(fp_line
			(start 0.120396 0.2794)
			(end -0.12065 0.2794)
			(stroke
				(width 0.1)
				(type default)
			)
			(layer "F.Fab")
		)
		(fp_line
			(start -0.12065 -0.2794)
			(end 0.12065 -0.2794)
			(stroke
				(width 0.1)
				(type default)
			)
			(layer "F.Fab")
		)
		(fp_line
			(start 0.12065 -0.2794)
			(end 0.12065 -0.3048)
			(stroke
				(width 0.1)
				(type default)
			)
			(layer "F.Fab")
		)
		(fp_line
			(start 0.12065 -0.3048)
			(end 0.67945 -0.3048)
			(stroke
				(width 0.1)
				(type default)
			)
			(layer "F.Fab")
		)
		(fp_line
			(start 0.67945 -0.3048)
			(end 0.67945 0.3048)
			(stroke
				(width 0.1)
				(type default)
			)
			(layer "F.Fab")
		)
		(fp_line
			(start -0.67945 -0.305054)
			(end -0.12065 -0.305054)
			(stroke
				(width 0.1)
				(type default)
			)
			(layer "F.Fab")
		)
		(fp_line
			(start -0.12065 -0.305054)
			(end -0.12065 -0.2794)
			(stroke
				(width 0.1)
				(type default)
			)
			(layer "F.Fab")
		)
		(pad "1" smd circle
			(at -0.40005 0 270)
			(size 0 0)
			(layers "F.Cu" "F.Mask" "F.Paste")
			(net "PVCCIN_CPU0")
		)
		(pad "2" smd circle
			(at 0.40005 0 270)
			(size 0 0)
			(layers "F.Cu" "F.Mask" "F.Paste")
			(net "GND")
		)
	)
	(footprint ""
		(layer "F.Cu")
		(at 302.641 -50.383948)
		(property "Reference" "C1249"
			(at 0 0 0)
			(layer "F.SilkS")
			(hide yes)
			(effects
				(font
					(size 1.27 1.27)
				)
			)
		)
		(property "Value" ""
			(at 0 0 0)
			(layer "F.Fab")
			(effects
				(font
					(size 1.27 1.27)
				)
			)
		)
		(duplicate_pad_numbers_are_jumpers no)
		(fp_line
			(start -1.524 -0.762)
			(end 1.524 -0.762)
			(stroke
				(width 0.1524)
				(type default)
			)
			(layer "F.SilkS")
		)
		(fp_line
			(start -1.524 0.762)
			(end -1.524 -0.762)
			(stroke
				(width 0.1524)
				(type default)
			)
			(layer "F.SilkS")
		)
		(fp_line
			(start 1.524 -0.762)
			(end 1.524 0.762)
			(stroke
				(width 0.1524)
				(type default)
			)
			(layer "F.SilkS")
		)
		(fp_line
			(start 1.524 0.762)
			(end -1.524 0.762)
			(stroke
				(width 0.1524)
				(type default)
			)
			(layer "F.SilkS")
		)
		(fp_line
			(start -1.1049 -0.724916)
			(end -1.1049 0.724916)
			(stroke
				(width 0.1)
				(type default)
			)
			(layer "F.Fab")
		)
		(fp_line
			(start -1.1049 0.724916)
			(end 1.1049 0.724916)
			(stroke
				(width 0.1)
				(type default)
			)
			(layer "F.Fab")
		)
		(fp_line
			(start 1.1049 -0.724916)
			(end -1.1049 -0.724916)
			(stroke
				(width 0.1)
				(type default)
			)
			(layer "F.Fab")
		)
		(fp_line
			(start 1.1049 0.724916)
			(end 1.1049 -0.724916)
			(stroke
				(width 0.1)
				(type default)
			)
			(layer "F.Fab")
		)
		(pad "1" smd rect
			(at -0.889 0 180)
			(size 1.016 1.27)
			(layers "F.Cu" "F.Mask" "F.Paste")
			(net "P1V05_PCH_AUX")
		)
		(pad "2" smd rect
			(at 0.889 0 180)
			(size 1.016 1.27)
			(layers "F.Cu" "F.Mask" "F.Paste")
			(net "GND")
		)
	)
	(footprint ""
		(layer "F.Cu")
		(at 177.9524 -93.538548 90)
		(property "Reference" "R4584"
			(at 0 0 90)
			(layer "F.SilkS")
			(hide yes)
			(effects
				(font
					(size 1.27 1.27)
				)
			)
		)
		(property "Value" ""
			(at 0 0 90)
			(layer "F.Fab")
			(effects
				(font
					(size 1.27 1.27)
				)
			)
		)
		(duplicate_pad_numbers_are_jumpers no)
		(fp_line
			(start 0.7874 -0.4064)
			(end 0.7874 0.4064)
			(stroke
				(width 0.1524)
				(type default)
			)
			(layer "F.SilkS")
		)
		(fp_line
			(start -0.7874 -0.4064)
			(end 0.7874 -0.4064)
			(stroke
				(width 0.1524)
				(type default)
			)
			(layer "F.SilkS")
		)
		(fp_line
			(start 0.7874 0.4064)
			(end -0.7874 0.4064)
			(stroke
				(width 0.1524)
				(type default)
			)
			(layer "F.SilkS")
		)
		(fp_line
			(start -0.7874 0.4064)
			(end -0.7874 -0.4064)
			(stroke
				(width 0.1524)
				(type default)
			)
			(layer "F.SilkS")
		)
		(fp_line
			(start -0.12065 -0.305054)
			(end -0.12065 -0.2794)
			(stroke
				(width 0.1)
				(type default)
			)
			(layer "F.Fab")
		)
		(fp_line
			(start -0.67945 -0.305054)
			(end -0.12065 -0.305054)
			(stroke
				(width 0.1)
				(type default)
			)
			(layer "F.Fab")
		)
		(fp_line
			(start 0.67945 -0.3048)
			(end 0.67945 0.3048)
			(stroke
				(width 0.1)
				(type default)
			)
			(layer "F.Fab")
		)
		(fp_line
			(start 0.12065 -0.3048)
			(end 0.67945 -0.3048)
			(stroke
				(width 0.1)
				(type default)
			)
			(layer "F.Fab")
		)
		(fp_line
			(start 0.12065 -0.2794)
			(end 0.12065 -0.3048)
			(stroke
				(width 0.1)
				(type default)
			)
			(layer "F.Fab")
		)
		(fp_line
			(start -0.12065 -0.2794)
			(end 0.12065 -0.2794)
			(stroke
				(width 0.1)
				(type default)
			)
			(layer "F.Fab")
		)
		(fp_line
			(start 0.120396 0.2794)
			(end -0.12065 0.2794)
			(stroke
				(width 0.1)
				(type default)
			)
			(layer "F.Fab")
		)
		(fp_line
			(start -0.12065 0.2794)
			(end -0.12065 0.3048)
			(stroke
				(width 0.1)
				(type default)
			)
			(layer "F.Fab")
		)
		(fp_line
			(start 0.67945 0.3048)
			(end 0.120396 0.3048)
			(stroke
				(width 0.1)
				(type default)
			)
			(layer "F.Fab")
		)
		(fp_line
			(start 0.120396 0.3048)
			(end 0.120396 0.2794)
			(stroke
				(width 0.1)
				(type default)
			)
			(layer "F.Fab")
		)
		(fp_line
			(start -0.12065 0.3048)
			(end -0.67945 0.3048)
			(stroke
				(width 0.1)
				(type default)
			)
			(layer "F.Fab")
		)
		(fp_line
			(start -0.67945 0.3048)
			(end -0.67945 -0.305054)
			(stroke
				(width 0.1)
				(type default)
			)
			(layer "F.Fab")
		)
		(pad "1" smd rect
			(at -0.40005 0 270)
			(size 0.4572 0.508)
			(layers "F.Cu" "F.Mask" "F.Paste")
			(net "P3V3_AUX")
		)
		(pad "2" smd rect
			(at 0.40005 0 270)
			(size 0.4572 0.508)
			(layers "F.Cu" "F.Mask" "F.Paste")
			(net "FM_BOARD_BMC_SKU_ID0")
		)
	)
)
